# S9S_MB_2U (Grand Teton) — schematic netlist excerpt (pin names and nets, part order shuffled) for the footprints in the layout excerpt that follows; sources: Cadence DE-HDL packaged netlist, KiCad conversion of 03242023_DA0F0TMBIJ0_F0T_Motherboard_J_brd_V01_OCP.brd

C1804  Q_CAP  1000PF 50V 5% EMPTY  pkg 0402  page 148 : A = FM_SMB_2_ALERT_GPU_ISO_N ; B = GND
C1404  Q_CAP  47UF 4V 20% X6S  pkg C0805  page 79 : A = PVNN_MAIN_CPU1 ; B = GND
R270  Q_RES  10K 1% CHIP  pkg 0402LF  page 119 : A = P3V3_AUX ; B = FM_CPU1_PKGID0

(kicad_pcb
	(version 20260206)
	(generator "pcbnew")
	(generator_version "10.0")
	(general
		(thickness 1.6)
		(legacy_teardrops no)
	)
	(paper "A4")
	(title_block
		(title "03242023_DA0F0TMBIJ0_F0T_Motherboard_J_brd_V01_OCP.brd")
		(comment 1 "Grand Teton / footprints 3730-3732 of 6105")
	)
	(layers
		(0 "F.Cu" signal "TOP")
		(4 "In1.Cu" signal "GND")
		(6 "In2.Cu" signal "IN1")
		(8 "In3.Cu" signal "GND1")
		(10 "In4.Cu" signal "IN2")
		(12 "In5.Cu" signal "GND2")
		(14 "In6.Cu" signal "IN3")
		(16 "In7.Cu" signal "GND3")
		(18 "In8.Cu" signal "VCC")
		(20 "In9.Cu" signal "VCC1")
		(22 "In10.Cu" signal "GND4")
		(24 "In11.Cu" signal "IN4")
		(26 "In12.Cu" signal "GND5")
		(28 "In13.Cu" signal "IN5")
		(30 "In14.Cu" signal "GND6")
		(32 "In15.Cu" signal "IN6")
		(34 "In16.Cu" signal "GND7")
		(2 "B.Cu" signal "BOTTOM")
		(9 "F.Adhes" user "F.Adhesive")
		(11 "B.Adhes" user "B.Adhesive")
		(13 "F.Paste" user "Package Geometry/Pastemask Top")
		(15 "B.Paste" user "Package Geometry/Pastemask Bottom")
		(5 "F.SilkS" user "Ref Des/Silkscreen Top")
		(7 "B.SilkS" user "Ref Des/Silkscreen Bottom")
		(1 "F.Mask" user "Board Geometry/Soldermask Top")
		(3 "B.Mask" user "Board Geometry/Soldermask Bottom")
		(17 "Dwgs.User" user "User.Drawings")
		(19 "Cmts.User" user "User.Comments")
		(21 "Eco1.User" user "User.Eco1")
		(23 "Eco2.User" user "User.Eco2")
		(25 "Edge.Cuts" user "Board Geometry/Outline")
		(27 "Margin" user)
		(31 "F.CrtYd" user "Package Geometry/Place Bound Top")
		(29 "B.CrtYd" user "Package Geometry/Place Bound Bottom")
		(35 "F.Fab" user "Ref Des/Assembly Top")
		(33 "B.Fab" user "Ref Des/Assembly Bottom")
	)
	(footprint ""
		(layer "F.Cu")
		(at 185.22188 -126.964948 -90)
		(property "Reference" "R270"
			(at 0 0 270)
			(layer "F.SilkS")
			(hide yes)
			(effects
				(font
					(size 1.27 1.27)
				)
			)
		)
		(property "Value" ""
			(at 0 0 270)
			(layer "F.Fab")
			(effects
				(font
					(size 1.27 1.27)
				)
			)
		)
		(duplicate_pad_numbers_are_jumpers no)
		(fp_line
			(start -0.7874 0.4064)
			(end -0.7874 -0.4064)
			(stroke
				(width 0.1524)
				(type default)
			)
			(layer "F.SilkS")
		)
		(fp_line
			(start 0.7874 0.4064)
			(end -0.7874 0.4064)
			(stroke
				(width 0.1524)
				(type default)
			)
			(layer "F.SilkS")
		)
		(fp_line
			(start -0.7874 -0.4064)
			(end 0.7874 -0.4064)
			(stroke
				(width 0.1524)
				(type default)
			)
			(layer "F.SilkS")
		)
		(fp_line
			(start 0.7874 -0.4064)
			(end 0.7874 0.4064)
			(stroke
				(width 0.1524)
				(type default)
			)
			(layer "F.SilkS")
		)
		(fp_line
			(start -0.67945 0.3048)
			(end -0.67945 -0.305054)
			(stroke
				(width 0.1)
				(type default)
			)
			(layer "F.Fab")
		)
		(fp_line
			(start -0.12065 0.3048)
			(end -0.67945 0.3048)
			(stroke
				(width 0.1)
				(type default)
			)
			(layer "F.Fab")
		)
		(fp_line
			(start 0.120396 0.3048)
			(end 0.120396 0.2794)
			(stroke
				(width 0.1)
				(type default)
			)
			(layer "F.Fab")
		)
		(fp_line
			(start 0.67945 0.3048)
			(end 0.120396 0.3048)
			(stroke
				(width 0.1)
				(type default)
			)
			(layer "F.Fab")
		)
		(fp_line
			(start -0.12065 0.2794)
			(end -0.12065 0.3048)
			(stroke
				(width 0.1)
				(type default)
			)
			(layer "F.Fab")
		)
		(fp_line
			(start 0.120396 0.2794)
			(end -0.12065 0.2794)
			(stroke
				(width 0.1)
				(type default)
			)
			(layer "F.Fab")
		)
		(fp_line
			(start -0.12065 -0.2794)
			(end 0.12065 -0.2794)
			(stroke
				(width 0.1)
				(type default)
			)
			(layer "F.Fab")
		)
		(fp_line
			(start 0.12065 -0.2794)
			(end 0.12065 -0.3048)
			(stroke
				(width 0.1)
				(type default)
			)
			(layer "F.Fab")
		)
		(fp_line
			(start 0.12065 -0.3048)
			(end 0.67945 -0.3048)
			(stroke
				(width 0.1)
				(type default)
			)
			(layer "F.Fab")
		)
		(fp_line
			(start 0.67945 -0.3048)
			(end 0.67945 0.3048)
			(stroke
				(width 0.1)
				(type default)
			)
			(layer "F.Fab")
		)
		(fp_line
			(start -0.67945 -0.305054)
			(end -0.12065 -0.305054)
			(stroke
				(width 0.1)
				(type default)
			)
			(layer "F.Fab")
		)
		(fp_line
			(start -0.12065 -0.305054)
			(end -0.12065 -0.2794)
			(stroke
				(width 0.1)
				(type default)
			)
			(layer "F.Fab")
		)
		(pad "1" smd circle
			(at -0.40005 0 270)
			(size 0 0)
			(layers "F.Cu" "F.Mask" "F.Paste")
			(net "P3V3_AUX")
		)
		(pad "2" smd circle
			(at 0.40005 0 270)
			(size 0 0)
			(layers "F.Cu" "F.Mask" "F.Paste")
			(net "FM_CPU1_PKGID0")
		)
	)
	(footprint ""
		(layer "F.Cu")
		(at 40.306498 -182.28564 180)
		(property "Reference" "C1404"
			(at 0 0 180)
			(layer "F.SilkS")
			(hide yes)
			(effects
				(font
					(size 1.27 1.27)
				)
			)
		)
		(property "Value" ""
			(at 0 0 180)
			(layer "F.Fab")
			(effects
				(font
					(size 1.27 1.27)
				)
			)
		)
		(duplicate_pad_numbers_are_jumpers no)
		(fp_line
			(start 1.524 0.762)
			(end -1.524 0.762)
			(stroke
				(width 0.1524)
				(type default)
			)
			(layer "F.SilkS")
		)
		(fp_line
			(start 1.524 -0.762)
			(end 1.524 0.762)
			(stroke
				(width 0.1524)
				(type default)
			)
			(layer "F.SilkS")
		)
		(fp_line
			(start -1.524 0.762)
			(end -1.524 -0.762)
			(stroke
				(width 0.1524)
				(type default)
			)
			(layer "F.SilkS")
		)
		(fp_line
			(start -1.524 -0.762)
			(end 1.524 -0.762)
			(stroke
				(width 0.1524)
				(type default)
			)
			(layer "F.SilkS")
		)
		(fp_line
			(start 1.1049 0.724916)
			(end 1.1049 -0.724916)
			(stroke
				(width 0.1)
				(type default)
			)
			(layer "F.Fab")
		)
		(fp_line
			(start 1.1049 -0.724916)
			(end -1.1049 -0.724916)
			(stroke
				(width 0.1)
				(type default)
			)
			(layer "F.Fab")
		)
		(fp_line
			(start -1.1049 0.724916)
			(end 1.1049 0.724916)
			(stroke
				(width 0.1)
				(type default)
			)
			(layer "F.Fab")
		)
		(fp_line
			(start -1.1049 -0.724916)
			(end -1.1049 0.724916)
			(stroke
				(width 0.1)
				(type default)
			)
			(layer "F.Fab")
		)
		(pad "1" smd rect
			(at -0.889 0)
			(size 1.016 1.27)
			(layers "F.Cu" "F.Mask" "F.Paste")
			(net "PVNN_MAIN_CPU1")
		)
		(pad "2" smd rect
			(at 0.889 0)
			(size 1.016 1.27)
			(layers "F.Cu" "F.Mask" "F.Paste")
			(net "GND")
		)
	)
	(footprint ""
		(layer "F.Cu")
		(at 111.25708 -397.874998 90)
		(property "Reference" "C1804"
			(at 0 0 90)
			(layer "F.SilkS")
			(hide yes)
			(effects
				(font
					(size 1.27 1.27)
				)
			)
		)
		(property "Value" ""
			(at 0 0 90)
			(layer "F.Fab")
			(effects
				(font
					(size 1.27 1.27)
				)
			)
		)
		(duplicate_pad_numbers_are_jumpers no)
		(fp_line
			(start 0.7874 -0.4064)
			(end 0.7874 0.4064)
			(stroke
				(width 0.1524)
				(type default)
			)
			(layer "F.SilkS")
		)
		(fp_line
			(start -0.7874 -0.4064)
			(end 0.7874 -0.4064)
			(stroke
				(width 0.1524)
				(type default)
			)
			(layer "F.SilkS")
		)
		(fp_line
			(start 0.7874 0.4064)
			(end -0.7874 0.4064)
			(stroke
				(width 0.1524)
				(type default)
			)
			(layer "F.SilkS")
		)
		(fp_line
			(start -0.7874 0.4064)
			(end -0.7874 -0.4064)
			(stroke
				(width 0.1524)
				(type default)
			)
			(layer "F.SilkS")
		)
		(fp_line
			(start -0.12065 -0.305054)
			(end -0.12065 -0.2794)
			(stroke
				(width 0.1)
				(type default)
			)
			(layer "F.Fab")
		)
		(fp_line
			(start -0.67945 -0.305054)
			(end -0.12065 -0.305054)
			(stroke
				(width 0.1)
				(type default)
			)
			(layer "F.Fab")
		)
		(fp_line
			(start 0.67945 -0.3048)
			(end 0.67945 0.3048)
			(stroke
				(width 0.1)
				(type default)
			)
			(layer "F.Fab")
		)
		(fp_line
			(start 0.12065 -0.3048)
			(end 0.67945 -0.3048)
			(stroke
				(width 0.1)
				(type default)
			)
			(layer "F.Fab")
		)
		(fp_line
			(start 0.12065 -0.2794)
			(end 0.12065 -0.3048)
			(stroke
				(width 0.1)
				(type default)
			)
			(layer "F.Fab")
		)
		(fp_line
			(start -0.12065 -0.2794)
			(end 0.12065 -0.2794)
			(stroke
				(width 0.1)
				(type default)
			)
			(layer "F.Fab")
		)
		(fp_line
			(start 0.120396 0.2794)
			(end -0.12065 0.2794)
			(stroke
				(width 0.1)
				(type default)
			)
			(layer "F.Fab")
		)
		(fp_line
			(start -0.12065 0.2794)
			(end -0.12065 0.3048)
			(stroke
				(width 0.1)
				(type default)
			)
			(layer "F.Fab")
		)
		(fp_line
			(start 0.67945 0.3048)
			(end 0.120396 0.3048)
			(stroke
				(width 0.1)
				(type default)
			)
			(layer "F.Fab")
		)
		(fp_line
			(start 0.120396 0.3048)
			(end 0.120396 0.2794)
			(stroke
				(width 0.1)
				(type default)
			)
			(layer "F.Fab")
		)
		(fp_line
			(start -0.12065 0.3048)
			(end -0.67945 0.3048)
			(stroke
				(width 0.1)
				(type default)
			)
			(layer "F.Fab")
		)
		(fp_line
			(start -0.67945 0.3048)
			(end -0.67945 -0.305054)
			(stroke
				(width 0.1)
				(type default)
			)
			(layer "F.Fab")
		)
		(pad "1" smd circle
			(at -0.40005 0 90)
			(size 0 0)
			(layers "F.Cu" "F.Mask" "F.Paste")
			(net "FM_SMB_2_ALERT_GPU_ISO_N")
		)
		(pad "2" smd circle
			(at 0.40005 0 90)
			(size 0 0)
			(layers "F.Cu" "F.Mask" "F.Paste")
			(net "GND")
		)
	)
)
